# S9S_MB_2U (Grand Teton) — schematic netlist excerpt (pin names and nets, part order shuffled) for the footprints in the layout excerpt that follows; sources: Cadence DE-HDL packaged netlist, KiCad conversion of 03242023_DA0F0TMBIJ0_F0T_Motherboard_J_brd_V01_OCP.brd

R486  Q_RES  0 5% CHIP  pkg 0402LF  page 190 : A = M2_SSD0_CLKREQ_EN_N ; B = M2_SSD0_CLKREQ_EN_N_BUF
R2693  Q_RES  1K 1% EMPTY  pkg 0402LF  page 227 : A = P3V3_AUX ; B = TCA9539_0_ADD1

(kicad_pcb
	(version 20260206)
	(generator "pcbnew")
	(generator_version "10.0")
	(general
		(thickness 1.6)
		(legacy_teardrops no)
	)
	(paper "A4")
	(title_block
		(title "03242023_DA0F0TMBIJ0_F0T_Motherboard_J_brd_V01_OCP.brd")
		(comment 1 "Grand Teton / footprints 3278-3279 of 6105")
	)
	(layers
		(0 "F.Cu" signal "TOP")
		(4 "In1.Cu" signal "GND")
		(6 "In2.Cu" signal "IN1")
		(8 "In3.Cu" signal "GND1")
		(10 "In4.Cu" signal "IN2")
		(12 "In5.Cu" signal "GND2")
		(14 "In6.Cu" signal "IN3")
		(16 "In7.Cu" signal "GND3")
		(18 "In8.Cu" signal "VCC")
		(20 "In9.Cu" signal "VCC1")
		(22 "In10.Cu" signal "GND4")
		(24 "In11.Cu" signal "IN4")
		(26 "In12.Cu" signal "GND5")
		(28 "In13.Cu" signal "IN5")
		(30 "In14.Cu" signal "GND6")
		(32 "In15.Cu" signal "IN6")
		(34 "In16.Cu" signal "GND7")
		(2 "B.Cu" signal "BOTTOM")
		(9 "F.Adhes" user "F.Adhesive")
		(11 "B.Adhes" user "B.Adhesive")
		(13 "F.Paste" user "Package Geometry/Pastemask Top")
		(15 "B.Paste" user "Package Geometry/Pastemask Bottom")
		(5 "F.SilkS" user "Ref Des/Silkscreen Top")
		(7 "B.SilkS" user "Ref Des/Silkscreen Bottom")
		(1 "F.Mask" user "Board Geometry/Soldermask Top")
		(3 "B.Mask" user "Board Geometry/Soldermask Bottom")
		(17 "Dwgs.User" user "User.Drawings")
		(19 "Cmts.User" user "User.Comments")
		(21 "Eco1.User" user "User.Eco1")
		(23 "Eco2.User" user "User.Eco2")
		(25 "Edge.Cuts" user "Board Geometry/Outline")
		(27 "Margin" user)
		(31 "F.CrtYd" user "Package Geometry/Place Bound Top")
		(29 "B.CrtYd" user "Package Geometry/Place Bound Bottom")
		(35 "F.Fab" user "Ref Des/Assembly Top")
		(33 "B.Fab" user "Ref Des/Assembly Bottom")
	)
	(footprint ""
		(layer "F.Cu")
		(at 13.800582 -410.802836 90)
		(property "Reference" "R2693"
			(at 0 0 90)
			(layer "F.SilkS")
			(hide yes)
			(effects
				(font
					(size 1.27 1.27)
				)
			)
		)
		(property "Value" ""
			(at 0 0 90)
			(layer "F.Fab")
			(effects
				(font
					(size 1.27 1.27)
				)
			)
		)
		(duplicate_pad_numbers_are_jumpers no)
		(fp_line
			(start 0.7874 -0.4064)
			(end 0.7874 0.4064)
			(stroke
				(width 0.1524)
				(type default)
			)
			(layer "F.SilkS")
		)
		(fp_line
			(start -0.7874 -0.4064)
			(end 0.7874 -0.4064)
			(stroke
				(width 0.1524)
				(type default)
			)
			(layer "F.SilkS")
		)
		(fp_line
			(start 0.7874 0.4064)
			(end -0.7874 0.4064)
			(stroke
				(width 0.1524)
				(type default)
			)
			(layer "F.SilkS")
		)
		(fp_line
			(start -0.7874 0.4064)
			(end -0.7874 -0.4064)
			(stroke
				(width 0.1524)
				(type default)
			)
			(layer "F.SilkS")
		)
		(fp_line
			(start -0.12065 -0.305054)
			(end -0.12065 -0.2794)
			(stroke
				(width 0.1)
				(type default)
			)
			(layer "F.Fab")
		)
		(fp_line
			(start -0.67945 -0.305054)
			(end -0.12065 -0.305054)
			(stroke
				(width 0.1)
				(type default)
			)
			(layer "F.Fab")
		)
		(fp_line
			(start 0.67945 -0.3048)
			(end 0.67945 0.3048)
			(stroke
				(width 0.1)
				(type default)
			)
			(layer "F.Fab")
		)
		(fp_line
			(start 0.12065 -0.3048)
			(end 0.67945 -0.3048)
			(stroke
				(width 0.1)
				(type default)
			)
			(layer "F.Fab")
		)
		(fp_line
			(start 0.12065 -0.2794)
			(end 0.12065 -0.3048)
			(stroke
				(width 0.1)
				(type default)
			)
			(layer "F.Fab")
		)
		(fp_line
			(start -0.12065 -0.2794)
			(end 0.12065 -0.2794)
			(stroke
				(width 0.1)
				(type default)
			)
			(layer "F.Fab")
		)
		(fp_line
			(start 0.120396 0.2794)
			(end -0.12065 0.2794)
			(stroke
				(width 0.1)
				(type default)
			)
			(layer "F.Fab")
		)
		(fp_line
			(start -0.12065 0.2794)
			(end -0.12065 0.3048)
			(stroke
				(width 0.1)
				(type default)
			)
			(layer "F.Fab")
		)
		(fp_line
			(start 0.67945 0.3048)
			(end 0.120396 0.3048)
			(stroke
				(width 0.1)
				(type default)
			)
			(layer "F.Fab")
		)
		(fp_line
			(start 0.120396 0.3048)
			(end 0.120396 0.2794)
			(stroke
				(width 0.1)
				(type default)
			)
			(layer "F.Fab")
		)
		(fp_line
			(start -0.12065 0.3048)
			(end -0.67945 0.3048)
			(stroke
				(width 0.1)
				(type default)
			)
			(layer "F.Fab")
		)
		(fp_line
			(start -0.67945 0.3048)
			(end -0.67945 -0.305054)
			(stroke
				(width 0.1)
				(type default)
			)
			(layer "F.Fab")
		)
		(pad "1" smd circle
			(at -0.40005 0 90)
			(size 0 0)
			(layers "F.Cu" "F.Mask" "F.Paste")
			(net "P3V3_AUX")
		)
		(pad "2" smd circle
			(at 0.40005 0 90)
			(size 0 0)
			(layers "F.Cu" "F.Mask" "F.Paste")
			(net "TCA9539_0_ADD1")
		)
	)
	(footprint ""
		(layer "F.Cu")
		(at 164.52088 -42.255948)
		(property "Reference" "R486"
			(at 0 0 0)
			(layer "F.SilkS")
			(hide yes)
			(effects
				(font
					(size 1.27 1.27)
				)
			)
		)
		(property "Value" ""
			(at 0 0 0)
			(layer "F.Fab")
			(effects
				(font
					(size 1.27 1.27)
				)
			)
		)
		(duplicate_pad_numbers_are_jumpers no)
		(fp_line
			(start -0.7874 -0.4064)
			(end 0.7874 -0.4064)
			(stroke
				(width 0.1524)
				(type default)
			)
			(layer "F.SilkS")
		)
		(fp_line
			(start -0.7874 0.4064)
			(end -0.7874 -0.4064)
			(stroke
				(width 0.1524)
				(type default)
			)
			(layer "F.SilkS")
		)
		(fp_line
			(start 0.7874 -0.4064)
			(end 0.7874 0.4064)
			(stroke
				(width 0.1524)
				(type default)
			)
			(layer "F.SilkS")
		)
		(fp_line
			(start 0.7874 0.4064)
			(end -0.7874 0.4064)
			(stroke
				(width 0.1524)
				(type default)
			)
			(layer "F.SilkS")
		)
		(fp_line
			(start -0.67945 -0.305054)
			(end -0.12065 -0.305054)
			(stroke
				(width 0.1)
				(type default)
			)
			(layer "F.Fab")
		)
		(fp_line
			(start -0.67945 0.3048)
			(end -0.67945 -0.305054)
			(stroke
				(width 0.1)
				(type default)
			)
			(layer "F.Fab")
		)
		(fp_line
			(start -0.12065 -0.305054)
			(end -0.12065 -0.2794)
			(stroke
				(width 0.1)
				(type default)
			)
			(layer "F.Fab")
		)
		(fp_line
			(start -0.12065 -0.2794)
			(end 0.12065 -0.2794)
			(stroke
				(width 0.1)
				(type default)
			)
			(layer "F.Fab")
		)
		(fp_line
			(start -0.12065 0.2794)
			(end -0.12065 0.3048)
			(stroke
				(width 0.1)
				(type default)
			)
			(layer "F.Fab")
		)
		(fp_line
			(start -0.12065 0.3048)
			(end -0.67945 0.3048)
			(stroke
				(width 0.1)
				(type default)
			)
			(layer "F.Fab")
		)
		(fp_line
			(start 0.120396 0.2794)
			(end -0.12065 0.2794)
			(stroke
				(width 0.1)
				(type default)
			)
			(layer "F.Fab")
		)
		(fp_line
			(start 0.120396 0.3048)
			(end 0.120396 0.2794)
			(stroke
				(width 0.1)
				(type default)
			)
			(layer "F.Fab")
		)
		(fp_line
			(start 0.12065 -0.3048)
			(end 0.67945 -0.3048)
			(stroke
				(width 0.1)
				(type default)
			)
			(layer "F.Fab")
		)
		(fp_line
			(start 0.12065 -0.2794)
			(end 0.12065 -0.3048)
			(stroke
				(width 0.1)
				(type default)
			)
			(layer "F.Fab")
		)
		(fp_line
			(start 0.67945 -0.3048)
			(end 0.67945 0.3048)
			(stroke
				(width 0.1)
				(type default)
			)
			(layer "F.Fab")
		)
		(fp_line
			(start 0.67945 0.3048)
			(end 0.120396 0.3048)
			(stroke
				(width 0.1)
				(type default)
			)
			(layer "F.Fab")
		)
		(pad "1" smd circle
			(at -0.40005 0)
			(size 0 0)
			(layers "F.Cu" "F.Mask" "F.Paste")
			(net "M2_SSD0_CLKREQ_EN_N")
		)
		(pad "2" smd circle
			(at 0.40005 0)
			(size 0 0)
			(layers "F.Cu" "F.Mask" "F.Paste")
			(net "M2_SSD0_CLKREQ_EN_N_BUF")
		)
	)
)
